# S9S_MB_2U (Grand Teton) — schematic netlist excerpt (pin names and nets, part order shuffled) for the footprints in the layout excerpt that follows; sources: Cadence DE-HDL packaged netlist, KiCad conversion of 03242023_DA0F0TMBIJ0_F0T_Motherboard_J_brd_V01_OCP.brd

PL24  Q_INDUCTOR4P_14  150NH IND  pkg L_TLM117513Q-151QL_11X7-5XA  page 288
  \1\  = SW_PVCCIN_CPU1_SW8
  \2\  = IND_P1_CPL8
  \3\  = IND_P1_CPL5
  \4\  = PVCCIN_CPU1

R1128  Q_RES  1K 1% CHIP  pkg 0402LF  page 158 : A = PD_SMB_OCP1_HP_ADD0 ; B = GND

(kicad_pcb
	(version 20260206)
	(generator "pcbnew")
	(generator_version "10.0")
	(general
		(thickness 1.6)
		(legacy_teardrops no)
	)
	(paper "A4")
	(title_block
		(title "03242023_DA0F0TMBIJ0_F0T_Motherboard_J_brd_V01_OCP.brd")
		(comment 1 "Grand Teton / footprints 2835-2836 of 6105")
	)
	(layers
		(0 "F.Cu" signal "TOP")
		(4 "In1.Cu" signal "GND")
		(6 "In2.Cu" signal "IN1")
		(8 "In3.Cu" signal "GND1")
		(10 "In4.Cu" signal "IN2")
		(12 "In5.Cu" signal "GND2")
		(14 "In6.Cu" signal "IN3")
		(16 "In7.Cu" signal "GND3")
		(18 "In8.Cu" signal "VCC")
		(20 "In9.Cu" signal "VCC1")
		(22 "In10.Cu" signal "GND4")
		(24 "In11.Cu" signal "IN4")
		(26 "In12.Cu" signal "GND5")
		(28 "In13.Cu" signal "IN5")
		(30 "In14.Cu" signal "GND6")
		(32 "In15.Cu" signal "IN6")
		(34 "In16.Cu" signal "GND7")
		(2 "B.Cu" signal "BOTTOM")
		(9 "F.Adhes" user "F.Adhesive")
		(11 "B.Adhes" user "B.Adhesive")
		(13 "F.Paste" user "Package Geometry/Pastemask Top")
		(15 "B.Paste" user "Package Geometry/Pastemask Bottom")
		(5 "F.SilkS" user "Ref Des/Silkscreen Top")
		(7 "B.SilkS" user "Ref Des/Silkscreen Bottom")
		(1 "F.Mask" user "Board Geometry/Soldermask Top")
		(3 "B.Mask" user "Board Geometry/Soldermask Bottom")
		(17 "Dwgs.User" user "User.Drawings")
		(19 "Cmts.User" user "User.Comments")
		(21 "Eco1.User" user "User.Eco1")
		(23 "Eco2.User" user "User.Eco2")
		(25 "Edge.Cuts" user "Board Geometry/Outline")
		(27 "Margin" user)
		(31 "F.CrtYd" user "Package Geometry/Place Bound Top")
		(29 "B.CrtYd" user "Package Geometry/Place Bound Bottom")
		(35 "F.Fab" user "Ref Des/Assembly Top")
		(33 "B.Fab" user "Ref Des/Assembly Bottom")
	)
	(footprint ""
		(layer "F.Cu")
		(at 137.91819 -333.55153)
		(property "Reference" "PL24"
			(at -0.359156 7.018274 0)
			(unlocked yes)
			(layer "F.SilkS")
			(effects
				(font
					(size 0.7874 0.5842)
					(thickness 0.1524)
				)
				(justify left)
			)
		)
		(property "Value" ""
			(at 0 0 0)
			(layer "F.Fab")
			(effects
				(font
					(size 1.27 1.27)
				)
			)
		)
		(duplicate_pad_numbers_are_jumpers no)
		(fp_line
			(start -3.750056 -5.500116)
			(end -2.393442 -5.500116)
			(stroke
				(width 0.1524)
				(type default)
			)
			(layer "F.SilkS")
		)
		(fp_line
			(start -3.750056 5.500116)
			(end -3.750056 -5.500116)
			(stroke
				(width 0.1524)
				(type default)
			)
			(layer "F.SilkS")
		)
		(fp_line
			(start -2.393442 5.500116)
			(end -3.750056 5.500116)
			(stroke
				(width 0.1524)
				(type default)
			)
			(layer "F.SilkS")
		)
		(fp_line
			(start 2.393442 5.500116)
			(end 3.750056 5.500116)
			(stroke
				(width 0.1524)
				(type default)
			)
			(layer "F.SilkS")
		)
		(fp_line
			(start 3.750056 -5.500116)
			(end 2.393442 -5.500116)
			(stroke
				(width 0.1524)
				(type default)
			)
			(layer "F.SilkS")
		)
		(fp_line
			(start 3.750056 5.500116)
			(end 3.750056 -5.500116)
			(stroke
				(width 0.1524)
				(type default)
			)
			(layer "F.SilkS")
		)
		(fp_poly
			(pts
				(xy -5.02666 -5.700268) (xy -4.01066 -5.192268) (xy -5.02666 -4.684268)
			)
			(stroke
				(width 0)
				(type default)
			)
			(fill yes)
			(layer "F.SilkS")
		)
		(fp_line
			(start -3.750056 -5.500116)
			(end -3.750056 5.500116)
			(stroke
				(width 0.1)
				(type default)
			)
			(layer "F.Fab")
		)
		(fp_line
			(start -3.750056 5.500116)
			(end 3.750056 5.500116)
			(stroke
				(width 0.1)
				(type default)
			)
			(layer "F.Fab")
		)
		(fp_line
			(start 3.750056 -5.500116)
			(end -3.750056 -5.500116)
			(stroke
				(width 0.1)
				(type default)
			)
			(layer "F.Fab")
		)
		(fp_line
			(start 3.750056 5.500116)
			(end 3.750056 -5.500116)
			(stroke
				(width 0.1)
				(type default)
			)
			(layer "F.Fab")
		)
		(fp_poly
			(pts
				(xy -4.9276 -4.757928) (xy -4.9276 -3.741928) (xy -3.9116 -4.249928)
			)
			(stroke
				(width 0)
				(type default)
			)
			(fill yes)
			(layer "F.Fab")
		)
		(pad "1" smd rect
			(at 0 -4.249928 270)
			(size 2.413 4.5212)
			(layers "F.Cu" "F.Mask" "F.Paste")
			(net "SW_PVCCIN_CPU1_SW8")
		)
		(pad "2" smd rect
			(at 0 -1.175004 270)
			(size 1.3716 4.5212)
			(layers "F.Cu" "F.Mask" "F.Paste")
			(net "IND_P1_CPL8")
		)
		(pad "3" smd rect
			(at 0 1.175004 270)
			(size 1.3716 4.5212)
			(layers "F.Cu" "F.Mask" "F.Paste")
			(net "IND_P1_CPL5")
		)
		(pad "4" smd rect
			(at 0 4.249928 270)
			(size 2.413 4.5212)
			(layers "F.Cu" "F.Mask" "F.Paste")
			(net "PVCCIN_CPU1")
		)
	)
	(footprint ""
		(layer "F.Cu")
		(at 465.821014 -116.616734)
		(property "Reference" "R1128"
			(at 0 0 0)
			(layer "F.SilkS")
			(hide yes)
			(effects
				(font
					(size 1.27 1.27)
				)
			)
		)
		(property "Value" ""
			(at 0 0 0)
			(layer "F.Fab")
			(effects
				(font
					(size 1.27 1.27)
				)
			)
		)
		(duplicate_pad_numbers_are_jumpers no)
		(fp_line
			(start -0.7874 -0.4064)
			(end 0.7874 -0.4064)
			(stroke
				(width 0.1524)
				(type default)
			)
			(layer "F.SilkS")
		)
		(fp_line
			(start -0.7874 0.4064)
			(end -0.7874 -0.4064)
			(stroke
				(width 0.1524)
				(type default)
			)
			(layer "F.SilkS")
		)
		(fp_line
			(start 0.7874 -0.4064)
			(end 0.7874 0.4064)
			(stroke
				(width 0.1524)
				(type default)
			)
			(layer "F.SilkS")
		)
		(fp_line
			(start 0.7874 0.4064)
			(end -0.7874 0.4064)
			(stroke
				(width 0.1524)
				(type default)
			)
			(layer "F.SilkS")
		)
		(fp_line
			(start -0.67945 -0.305054)
			(end -0.12065 -0.305054)
			(stroke
				(width 0.1)
				(type default)
			)
			(layer "F.Fab")
		)
		(fp_line
			(start -0.67945 0.3048)
			(end -0.67945 -0.305054)
			(stroke
				(width 0.1)
				(type default)
			)
			(layer "F.Fab")
		)
		(fp_line
			(start -0.12065 -0.305054)
			(end -0.12065 -0.2794)
			(stroke
				(width 0.1)
				(type default)
			)
			(layer "F.Fab")
		)
		(fp_line
			(start -0.12065 -0.2794)
			(end 0.12065 -0.2794)
			(stroke
				(width 0.1)
				(type default)
			)
			(layer "F.Fab")
		)
		(fp_line
			(start -0.12065 0.2794)
			(end -0.12065 0.3048)
			(stroke
				(width 0.1)
				(type default)
			)
			(layer "F.Fab")
		)
		(fp_line
			(start -0.12065 0.3048)
			(end -0.67945 0.3048)
			(stroke
				(width 0.1)
				(type default)
			)
			(layer "F.Fab")
		)
		(fp_line
			(start 0.120396 0.2794)
			(end -0.12065 0.2794)
			(stroke
				(width 0.1)
				(type default)
			)
			(layer "F.Fab")
		)
		(fp_line
			(start 0.120396 0.3048)
			(end 0.120396 0.2794)
			(stroke
				(width 0.1)
				(type default)
			)
			(layer "F.Fab")
		)
		(fp_line
			(start 0.12065 -0.3048)
			(end 0.67945 -0.3048)
			(stroke
				(width 0.1)
				(type default)
			)
			(layer "F.Fab")
		)
		(fp_line
			(start 0.12065 -0.2794)
			(end 0.12065 -0.3048)
			(stroke
				(width 0.1)
				(type default)
			)
			(layer "F.Fab")
		)
		(fp_line
			(start 0.67945 -0.3048)
			(end 0.67945 0.3048)
			(stroke
				(width 0.1)
				(type default)
			)
			(layer "F.Fab")
		)
		(fp_line
			(start 0.67945 0.3048)
			(end 0.120396 0.3048)
			(stroke
				(width 0.1)
				(type default)
			)
			(layer "F.Fab")
		)
		(pad "1" smd circle
			(at -0.40005 0)
			(size 0 0)
			(layers "F.Cu" "F.Mask" "F.Paste")
			(net "PD_SMB_OCP1_HP_ADD0")
		)
		(pad "2" smd circle
			(at 0.40005 0)
			(size 0 0)
			(layers "F.Cu" "F.Mask" "F.Paste")
			(net "GND")
		)
	)
)
